(kicad_pcb
	(version 20260206)
	(generator "pcbnew")
	(generator_version "10.0")
	(general
		(thickness 1.6)
		(legacy_teardrops no)
	)
	(paper "A4")
	(title_block
		(title "03242023_DA0F0TMBIJ0_F0T_Motherboard_J_brd_V01_OCP.brd")
		(comment 1 "Grand Teton / footprints 476-483 of 6105")
	)
	(layers
		(0 "F.Cu" signal "TOP")
		(4 "In1.Cu" signal "GND")
		(6 "In2.Cu" signal "IN1")
		(8 "In3.Cu" signal "GND1")
		(10 "In4.Cu" signal "IN2")
		(12 "In5.Cu" signal "GND2")
		(14 "In6.Cu" signal "IN3")
		(16 "In7.Cu" signal "GND3")
		(18 "In8.Cu" signal "VCC")
		(20 "In9.Cu" signal "VCC1")
		(22 "In10.Cu" signal "GND4")
		(24 "In11.Cu" signal "IN4")
		(26 "In12.Cu" signal "GND5")
		(28 "In13.Cu" signal "IN5")
		(30 "In14.Cu" signal "GND6")
		(32 "In15.Cu" signal "IN6")
		(34 "In16.Cu" signal "GND7")
		(2 "B.Cu" signal "BOTTOM")
		(9 "F.Adhes" user "F.Adhesive")
		(11 "B.Adhes" user "B.Adhesive")
		(13 "F.Paste" user "Package Geometry/Pastemask Top")
		(15 "B.Paste" user "Package Geometry/Pastemask Bottom")
		(5 "F.SilkS" user "Ref Des/Silkscreen Top")
		(7 "B.SilkS" user "Ref Des/Silkscreen Bottom")
		(1 "F.Mask" user "Board Geometry/Soldermask Top")
		(3 "B.Mask" user "Board Geometry/Soldermask Bottom")
		(17 "Dwgs.User" user "User.Drawings")
		(19 "Cmts.User" user "User.Comments")
		(21 "Eco1.User" user "User.Eco1")
		(23 "Eco2.User" user "User.Eco2")
		(25 "Edge.Cuts" user "Board Geometry/Outline")
		(27 "Margin" user)
		(31 "F.CrtYd" user "Package Geometry/Place Bound Top")
		(29 "B.CrtYd" user "Package Geometry/Place Bound Bottom")
		(35 "F.Fab" user "Ref Des/Assembly Top")
		(33 "B.Fab" user "Ref Des/Assembly Bottom")
	)
	(footprint ""
		(layer "F.Cu")
		(at 193.60388 -103.685848 180)
		(property "Reference" "R3045"
			(at 0 0 180)
			(layer "F.SilkS")
			(hide yes)
			(effects
				(font
					(size 1.27 1.27)
				)
			)
		)
		(property "Value" ""
			(at 0 0 180)
			(layer "F.Fab")
			(effects
				(font
					(size 1.27 1.27)
				)
			)
		)
		(duplicate_pad_numbers_are_jumpers no)
		(fp_line
			(start 0.7874 0.4064)
			(end -0.7874 0.4064)
			(stroke
				(width 0.1524)
				(type default)
			)
			(layer "F.SilkS")
		)
		(fp_line
			(start 0.7874 -0.4064)
			(end 0.7874 0.4064)
			(stroke
				(width 0.1524)
				(type default)
			)
			(layer "F.SilkS")
		)
		(fp_line
			(start -0.7874 0.4064)
			(end -0.7874 -0.4064)
			(stroke
				(width 0.1524)
				(type default)
			)
			(layer "F.SilkS")
		)
		(fp_line
			(start -0.7874 -0.4064)
			(end 0.7874 -0.4064)
			(stroke
				(width 0.1524)
				(type default)
			)
			(layer "F.SilkS")
		)
		(fp_line
			(start 0.67945 0.3048)
			(end 0.120396 0.3048)
			(stroke
				(width 0.1)
				(type default)
			)
			(layer "F.Fab")
		)
		(fp_line
			(start 0.67945 -0.3048)
			(end 0.67945 0.3048)
			(stroke
				(width 0.1)
				(type default)
			)
			(layer "F.Fab")
		)
		(fp_line
			(start 0.12065 -0.2794)
			(end 0.12065 -0.3048)
			(stroke
				(width 0.1)
				(type default)
			)
			(layer "F.Fab")
		)
		(fp_line
			(start 0.12065 -0.3048)
			(end 0.67945 -0.3048)
			(stroke
				(width 0.1)
				(type default)
			)
			(layer "F.Fab")
		)
		(fp_line
			(start 0.120396 0.3048)
			(end 0.120396 0.2794)
			(stroke
				(width 0.1)
				(type default)
			)
			(layer "F.Fab")
		)
		(fp_line
			(start 0.120396 0.2794)
			(end -0.12065 0.2794)
			(stroke
				(width 0.1)
				(type default)
			)
			(layer "F.Fab")
		)
		(fp_line
			(start -0.12065 0.3048)
			(end -0.67945 0.3048)
			(stroke
				(width 0.1)
				(type default)
			)
			(layer "F.Fab")
		)
		(fp_line
			(start -0.12065 0.2794)
			(end -0.12065 0.3048)
			(stroke
				(width 0.1)
				(type default)
			)
			(layer "F.Fab")
		)
		(fp_line
			(start -0.12065 -0.2794)
			(end 0.12065 -0.2794)
			(stroke
				(width 0.1)
				(type default)
			)
			(layer "F.Fab")
		)
		(fp_line
			(start -0.12065 -0.305054)
			(end -0.12065 -0.2794)
			(stroke
				(width 0.1)
				(type default)
			)
			(layer "F.Fab")
		)
		(fp_line
			(start -0.67945 0.3048)
			(end -0.67945 -0.305054)
			(stroke
				(width 0.1)
				(type default)
			)
			(layer "F.Fab")
		)
		(fp_line
			(start -0.67945 -0.305054)
			(end -0.12065 -0.305054)
			(stroke
				(width 0.1)
				(type default)
			)
			(layer "F.Fab")
		)
		(pad "1" smd circle
			(at -0.40005 0 180)
			(size 0 0)
			(layers "F.Cu" "F.Mask" "F.Paste")
			(net "IRQ_UV_DETECT_N")
		)
		(pad "2" smd circle
			(at 0.40005 0 180)
			(size 0 0)
			(layers "F.Cu" "F.Mask" "F.Paste")
			(net "IRQ_UV_DETECT_R_N")
		)
	)
	(footprint ""
		(layer "F.Cu")
		(at 106.70921 -413.687768 180)
		(property "Reference" "R3354"
			(at 0 0 180)
			(layer "F.SilkS")
			(hide yes)
			(effects
				(font
					(size 1.27 1.27)
				)
			)
		)
		(property "Value" ""
			(at 0 0 180)
			(layer "F.Fab")
			(effects
				(font
					(size 1.27 1.27)
				)
			)
		)
		(duplicate_pad_numbers_are_jumpers no)
		(fp_line
			(start 0.7874 0.4064)
			(end -0.7874 0.4064)
			(stroke
				(width 0.1524)
				(type default)
			)
			(layer "F.SilkS")
		)
		(fp_line
			(start 0.7874 0.01016)
			(end 0.7874 0.4064)
			(stroke
				(width 0.1524)
				(type default)
			)
			(layer "F.SilkS")
		)
		(fp_line
			(start -0.40767 -0.4064)
			(end 0.44323 -0.4064)
			(stroke
				(width 0.1524)
				(type default)
			)
			(layer "F.SilkS")
		)
		(fp_line
			(start -0.7874 0.4064)
			(end -0.7874 -0.03556)
			(stroke
				(width 0.1524)
				(type default)
			)
			(layer "F.SilkS")
		)
		(fp_line
			(start 0.67945 0.3048)
			(end 0.120396 0.3048)
			(stroke
				(width 0.1)
				(type default)
			)
			(layer "F.Fab")
		)
		(fp_line
			(start 0.67945 -0.3048)
			(end 0.67945 0.3048)
			(stroke
				(width 0.1)
				(type default)
			)
			(layer "F.Fab")
		)
		(fp_line
			(start 0.12065 -0.2794)
			(end 0.12065 -0.3048)
			(stroke
				(width 0.1)
				(type default)
			)
			(layer "F.Fab")
		)
		(fp_line
			(start 0.12065 -0.3048)
			(end 0.67945 -0.3048)
			(stroke
				(width 0.1)
				(type default)
			)
			(layer "F.Fab")
		)
		(fp_line
			(start 0.120396 0.3048)
			(end 0.120396 0.2794)
			(stroke
				(width 0.1)
				(type default)
			)
			(layer "F.Fab")
		)
		(fp_line
			(start 0.120396 0.2794)
			(end -0.12065 0.2794)
			(stroke
				(width 0.1)
				(type default)
			)
			(layer "F.Fab")
		)
		(fp_line
			(start -0.12065 0.3048)
			(end -0.67945 0.3048)
			(stroke
				(width 0.1)
				(type default)
			)
			(layer "F.Fab")
		)
		(fp_line
			(start -0.12065 0.2794)
			(end -0.12065 0.3048)
			(stroke
				(width 0.1)
				(type default)
			)
			(layer "F.Fab")
		)
		(fp_line
			(start -0.12065 -0.2794)
			(end 0.12065 -0.2794)
			(stroke
				(width 0.1)
				(type default)
			)
			(layer "F.Fab")
		)
		(fp_line
			(start -0.12065 -0.305054)
			(end -0.12065 -0.2794)
			(stroke
				(width 0.1)
				(type default)
			)
			(layer "F.Fab")
		)
		(fp_line
			(start -0.67945 0.3048)
			(end -0.67945 -0.305054)
			(stroke
				(width 0.1)
				(type default)
			)
			(layer "F.Fab")
		)
		(fp_line
			(start -0.67945 -0.305054)
			(end -0.12065 -0.305054)
			(stroke
				(width 0.1)
				(type default)
			)
			(layer "F.Fab")
		)
		(pad "1" smd circle
			(at -0.40005 0 180)
			(size 0 0)
			(layers "F.Cu" "F.Mask" "F.Paste")
			(net "CLK_100M_GPU_2_R_DP")
		)
		(pad "2" smd circle
			(at 0.40005 0 180)
			(size 0 0)
			(layers "F.Cu" "F.Mask" "F.Paste")
			(net "CLK_100M_GPU_2_DP")
		)
	)
	(footprint ""
		(layer "F.Cu")
		(at 228.410008 -402.994622 90)
		(property "Reference" "PC2223"
			(at 0 0 90)
			(layer "F.SilkS")
			(hide yes)
			(effects
				(font
					(size 1.27 1.27)
				)
			)
		)
		(property "Value" ""
			(at 0 0 90)
			(layer "F.Fab")
			(effects
				(font
					(size 1.27 1.27)
				)
			)
		)
		(duplicate_pad_numbers_are_jumpers no)
		(fp_line
			(start 0.7874 -0.4064)
			(end 0.7874 0.4064)
			(stroke
				(width 0.1524)
				(type default)
			)
			(layer "F.SilkS")
		)
		(fp_line
			(start -0.7874 -0.4064)
			(end 0.7874 -0.4064)
			(stroke
				(width 0.1524)
				(type default)
			)
			(layer "F.SilkS")
		)
		(fp_line
			(start 0.7874 0.4064)
			(end -0.7874 0.4064)
			(stroke
				(width 0.1524)
				(type default)
			)
			(layer "F.SilkS")
		)
		(fp_line
			(start -0.7874 0.4064)
			(end -0.7874 -0.4064)
			(stroke
				(width 0.1524)
				(type default)
			)
			(layer "F.SilkS")
		)
		(fp_line
			(start -0.12065 -0.305054)
			(end -0.12065 -0.2794)
			(stroke
				(width 0.1)
				(type default)
			)
			(layer "F.Fab")
		)
		(fp_line
			(start -0.67945 -0.305054)
			(end -0.12065 -0.305054)
			(stroke
				(width 0.1)
				(type default)
			)
			(layer "F.Fab")
		)
		(fp_line
			(start 0.67945 -0.3048)
			(end 0.67945 0.3048)
			(stroke
				(width 0.1)
				(type default)
			)
			(layer "F.Fab")
		)
		(fp_line
			(start 0.12065 -0.3048)
			(end 0.67945 -0.3048)
			(stroke
				(width 0.1)
				(type default)
			)
			(layer "F.Fab")
		)
		(fp_line
			(start 0.12065 -0.2794)
			(end 0.12065 -0.3048)
			(stroke
				(width 0.1)
				(type default)
			)
			(layer "F.Fab")
		)
		(fp_line
			(start -0.12065 -0.2794)
			(end 0.12065 -0.2794)
			(stroke
				(width 0.1)
				(type default)
			)
			(layer "F.Fab")
		)
		(fp_line
			(start 0.120396 0.2794)
			(end -0.12065 0.2794)
			(stroke
				(width 0.1)
				(type default)
			)
			(layer "F.Fab")
		)
		(fp_line
			(start -0.12065 0.2794)
			(end -0.12065 0.3048)
			(stroke
				(width 0.1)
				(type default)
			)
			(layer "F.Fab")
		)
		(fp_line
			(start 0.67945 0.3048)
			(end 0.120396 0.3048)
			(stroke
				(width 0.1)
				(type default)
			)
			(layer "F.Fab")
		)
		(fp_line
			(start 0.120396 0.3048)
			(end 0.120396 0.2794)
			(stroke
				(width 0.1)
				(type default)
			)
			(layer "F.Fab")
		)
		(fp_line
			(start -0.12065 0.3048)
			(end -0.67945 0.3048)
			(stroke
				(width 0.1)
				(type default)
			)
			(layer "F.Fab")
		)
		(fp_line
			(start -0.67945 0.3048)
			(end -0.67945 -0.305054)
			(stroke
				(width 0.1)
				(type default)
			)
			(layer "F.Fab")
		)
		(pad "1" smd circle
			(at -0.40005 0 90)
			(size 0 0)
			(layers "F.Cu" "F.Mask" "F.Paste")
			(net "HSC_VDD_R_4")
		)
		(pad "2" smd circle
			(at 0.40005 0 90)
			(size 0 0)
			(layers "F.Cu" "F.Mask" "F.Paste")
			(net "AGND_HSC")
		)
	)
	(footprint ""
		(layer "F.Cu")
		(at 236.649768 -352.49993)
		(property "Reference" "H95"
			(at -5.03682 -5.100828 0)
			(unlocked yes)
			(layer "F.SilkS")
			(effects
				(font
					(size 0.7874 0.5842)
					(thickness 0.1524)
				)
				(justify left)
			)
		)
		(property "Value" ""
			(at 0 0 0)
			(layer "F.Fab")
			(effects
				(font
					(size 1.27 1.27)
				)
			)
		)
		(duplicate_pad_numbers_are_jumpers no)
		(pad "1" thru_hole circle
			(at 0 0)
			(size 10.0076 10.0076)
			(drill 5.6134)
			(layers "*.Cu" "*.Mask")
			(remove_unused_layers no)
			(net "GND")
			(clearance -1.9431)
		)
	)
	(footprint ""
		(layer "F.Cu")
		(at 387.62813 -402.371052 -90)
		(property "Reference" "C944"
			(at 0 0 270)
			(layer "F.SilkS")
			(hide yes)
			(effects
				(font
					(size 1.27 1.27)
				)
			)
		)
		(property "Value" ""
			(at 0 0 270)
			(layer "F.Fab")
			(effects
				(font
					(size 1.27 1.27)
				)
			)
		)
		(duplicate_pad_numbers_are_jumpers no)
		(fp_line
			(start -0.299974 0.150114)
			(end -0.299974 -0.150114)
			(stroke
				(width 0.1)
				(type default)
			)
			(layer "F.Fab")
		)
		(fp_line
			(start 0.299974 0.150114)
			(end -0.299974 0.150114)
			(stroke
				(width 0.1)
				(type default)
			)
			(layer "F.Fab")
		)
		(fp_line
			(start -0.299974 -0.150114)
			(end 0.299974 -0.150114)
			(stroke
				(width 0.1)
				(type default)
			)
			(layer "F.Fab")
		)
		(fp_line
			(start 0.299974 -0.150114)
			(end 0.299974 0.150114)
			(stroke
				(width 0.1)
				(type default)
			)
			(layer "F.Fab")
		)
		(pad "1" smd rect
			(at -0.2667 0 270)
			(size 0.3048 0.381)
			(layers "F.Cu" "F.Mask" "F.Paste")
			(net "P5E_CPU0_PE2_TX_C_DN<10>")
		)
		(pad "2" smd rect
			(at 0.2667 0 270)
			(size 0.3048 0.381)
			(layers "F.Cu" "F.Mask" "F.Paste")
			(net "P5E_CPU0_PE2_TX_DN<10>")
		)
	)
	(footprint ""
		(layer "F.Cu")
		(at 309.278528 -408.517344 -90)
		(property "Reference" "C905"
			(at 0 0 270)
			(layer "F.SilkS")
			(hide yes)
			(effects
				(font
					(size 1.27 1.27)
				)
			)
		)
		(property "Value" ""
			(at 0 0 270)
			(layer "F.Fab")
			(effects
				(font
					(size 1.27 1.27)
				)
			)
		)
		(duplicate_pad_numbers_are_jumpers no)
		(fp_line
			(start -0.299974 0.150114)
			(end -0.299974 -0.150114)
			(stroke
				(width 0.1)
				(type default)
			)
			(layer "F.Fab")
		)
		(fp_line
			(start 0.299974 0.150114)
			(end -0.299974 0.150114)
			(stroke
				(width 0.1)
				(type default)
			)
			(layer "F.Fab")
		)
		(fp_line
			(start -0.299974 -0.150114)
			(end 0.299974 -0.150114)
			(stroke
				(width 0.1)
				(type default)
			)
			(layer "F.Fab")
		)
		(fp_line
			(start 0.299974 -0.150114)
			(end 0.299974 0.150114)
			(stroke
				(width 0.1)
				(type default)
			)
			(layer "F.Fab")
		)
		(pad "1" smd rect
			(at -0.2667 0 270)
			(size 0.3048 0.381)
			(layers "F.Cu" "F.Mask" "F.Paste")
			(net "P5E_CPU0_PE0_TX_C_DP<14>")
		)
		(pad "2" smd rect
			(at 0.2667 0 270)
			(size 0.3048 0.381)
			(layers "F.Cu" "F.Mask" "F.Paste")
			(net "P5E_CPU0_PE0_TX_DP<14>")
		)
	)
	(footprint ""
		(layer "F.Cu")
		(at 374.275858 -421.525446 -90)
		(property "Reference" "C2010"
			(at 0 0 270)
			(layer "F.SilkS")
			(hide yes)
			(effects
				(font
					(size 1.27 1.27)
				)
			)
		)
		(property "Value" ""
			(at 0 0 270)
			(layer "F.Fab")
			(effects
				(font
					(size 1.27 1.27)
				)
			)
		)
		(duplicate_pad_numbers_are_jumpers no)
		(fp_line
			(start -0.7874 0.4064)
			(end -0.7874 -0.4064)
			(stroke
				(width 0.1524)
				(type default)
			)
			(layer "F.SilkS")
		)
		(fp_line
			(start 0.7874 0.4064)
			(end -0.7874 0.4064)
			(stroke
				(width 0.1524)
				(type default)
			)
			(layer "F.SilkS")
		)
		(fp_line
			(start -0.7874 -0.4064)
			(end 0.7874 -0.4064)
			(stroke
				(width 0.1524)
				(type default)
			)
			(layer "F.SilkS")
		)
		(fp_line
			(start 0.7874 -0.4064)
			(end 0.7874 0.4064)
			(stroke
				(width 0.1524)
				(type default)
			)
			(layer "F.SilkS")
		)
		(fp_line
			(start -0.67945 0.3048)
			(end -0.67945 -0.305054)
			(stroke
				(width 0.1)
				(type default)
			)
			(layer "F.Fab")
		)
		(fp_line
			(start -0.12065 0.3048)
			(end -0.67945 0.3048)
			(stroke
				(width 0.1)
				(type default)
			)
			(layer "F.Fab")
		)
		(fp_line
			(start 0.120396 0.3048)
			(end 0.120396 0.2794)
			(stroke
				(width 0.1)
				(type default)
			)
			(layer "F.Fab")
		)
		(fp_line
			(start 0.67945 0.3048)
			(end 0.120396 0.3048)
			(stroke
				(width 0.1)
				(type default)
			)
			(layer "F.Fab")
		)
		(fp_line
			(start -0.12065 0.2794)
			(end -0.12065 0.3048)
			(stroke
				(width 0.1)
				(type default)
			)
			(layer "F.Fab")
		)
		(fp_line
			(start 0.120396 0.2794)
			(end -0.12065 0.2794)
			(stroke
				(width 0.1)
				(type default)
			)
			(layer "F.Fab")
		)
		(fp_line
			(start -0.12065 -0.2794)
			(end 0.12065 -0.2794)
			(stroke
				(width 0.1)
				(type default)
			)
			(layer "F.Fab")
		)
		(fp_line
			(start 0.12065 -0.2794)
			(end 0.12065 -0.3048)
			(stroke
				(width 0.1)
				(type default)
			)
			(layer "F.Fab")
		)
		(fp_line
			(start 0.12065 -0.3048)
			(end 0.67945 -0.3048)
			(stroke
				(width 0.1)
				(type default)
			)
			(layer "F.Fab")
		)
		(fp_line
			(start 0.67945 -0.3048)
			(end 0.67945 0.3048)
			(stroke
				(width 0.1)
				(type default)
			)
			(layer "F.Fab")
		)
		(fp_line
			(start -0.67945 -0.305054)
			(end -0.12065 -0.305054)
			(stroke
				(width 0.1)
				(type default)
			)
			(layer "F.Fab")
		)
		(fp_line
			(start -0.12065 -0.305054)
			(end -0.12065 -0.2794)
			(stroke
				(width 0.1)
				(type default)
			)
			(layer "F.Fab")
		)
		(pad "1" smd circle
			(at -0.40005 0 270)
			(size 0 0)
			(layers "F.Cu" "F.Mask" "F.Paste")
			(net "P3V3_AUX")
		)
		(pad "2" smd circle
			(at 0.40005 0 270)
			(size 0 0)
			(layers "F.Cu" "F.Mask" "F.Paste")
			(net "GND")
		)
	)
	(footprint ""
		(layer "F.Cu")
		(at 263.55294 -133.005068 180)
		(property "Reference" "R4541"
			(at 0 0 180)
			(layer "F.SilkS")
			(hide yes)
			(effects
				(font
					(size 1.27 1.27)
				)
			)
		)
		(property "Value" ""
			(at 0 0 180)
			(layer "F.Fab")
			(effects
				(font
					(size 1.27 1.27)
				)
			)
		)
		(duplicate_pad_numbers_are_jumpers no)
		(fp_line
			(start 0.7874 0.4064)
			(end -0.7874 0.4064)
			(stroke
				(width 0.1524)
				(type default)
			)
			(layer "F.SilkS")
		)
		(fp_line
			(start 0.7874 -0.4064)
			(end 0.7874 0.4064)
			(stroke
				(width 0.1524)
				(type default)
			)
			(layer "F.SilkS")
		)
		(fp_line
			(start -0.7874 0.4064)
			(end -0.7874 -0.4064)
			(stroke
				(width 0.1524)
				(type default)
			)
			(layer "F.SilkS")
		)
		(fp_line
			(start -0.7874 -0.4064)
			(end 0.7874 -0.4064)
			(stroke
				(width 0.1524)
				(type default)
			)
			(layer "F.SilkS")
		)
		(fp_line
			(start 0.67945 0.3048)
			(end 0.120396 0.3048)
			(stroke
				(width 0.1)
				(type default)
			)
			(layer "F.Fab")
		)
		(fp_line
			(start 0.67945 -0.3048)
			(end 0.67945 0.3048)
			(stroke
				(width 0.1)
				(type default)
			)
			(layer "F.Fab")
		)
		(fp_line
			(start 0.12065 -0.2794)
			(end 0.12065 -0.3048)
			(stroke
				(width 0.1)
				(type default)
			)
			(layer "F.Fab")
		)
		(fp_line
			(start 0.12065 -0.3048)
			(end 0.67945 -0.3048)
			(stroke
				(width 0.1)
				(type default)
			)
			(layer "F.Fab")
		)
		(fp_line
			(start 0.120396 0.3048)
			(end 0.120396 0.2794)
			(stroke
				(width 0.1)
				(type default)
			)
			(layer "F.Fab")
		)
		(fp_line
			(start 0.120396 0.2794)
			(end -0.12065 0.2794)
			(stroke
				(width 0.1)
				(type default)
			)
			(layer "F.Fab")
		)
		(fp_line
			(start -0.12065 0.3048)
			(end -0.67945 0.3048)
			(stroke
				(width 0.1)
				(type default)
			)
			(layer "F.Fab")
		)
		(fp_line
			(start -0.12065 0.2794)
			(end -0.12065 0.3048)
			(stroke
				(width 0.1)
				(type default)
			)
			(layer "F.Fab")
		)
		(fp_line
			(start -0.12065 -0.2794)
			(end 0.12065 -0.2794)
			(stroke
				(width 0.1)
				(type default)
			)
			(layer "F.Fab")
		)
		(fp_line
			(start -0.12065 -0.305054)
			(end -0.12065 -0.2794)
			(stroke
				(width 0.1)
				(type default)
			)
			(layer "F.Fab")
		)
		(fp_line
			(start -0.67945 0.3048)
			(end -0.67945 -0.305054)
			(stroke
				(width 0.1)
				(type default)
			)
			(layer "F.Fab")
		)
		(fp_line
			(start -0.67945 -0.305054)
			(end -0.12065 -0.305054)
			(stroke
				(width 0.1)
				(type default)
			)
			(layer "F.Fab")
		)
		(pad "1" smd circle
			(at -0.40005 0 180)
			(size 0 0)
			(layers "F.Cu" "F.Mask" "F.Paste")
			(net "SMB_HOST_CLK_BUF_ISO_3V3AUX_S_2")
		)
		(pad "2" smd circle
			(at 0.40005 0 180)
			(size 0 0)
			(layers "F.Cu" "F.Mask" "F.Paste")
			(net "SMB_HOST_CLK_BUF_ISO_3V3AUX_SDA")
		)
	)
)
